# S9S_MB_2U (Grand Teton) — schematic netlist excerpt (pin names and nets, part order shuffled) for the footprints in the layout excerpt that follows; sources: Cadence DE-HDL packaged netlist, KiCad conversion of 03242023_DA0F0TMBIJ0_F0T_Motherboard_J_brd_V01_OCP.brd

C61  Q_CAP  10UF 16V 10% X6S  pkg C0805  page 101 : A = P12V_S3_AUX_CPU1_NVDIMM ; B = GND
C1884  Q_CAP  1UF 25V 10% X6S  pkg C0402  page 212 : A = VFG_3P3A_CLK_GEN ; B = GND
PC241_P0_7  Q_CAP  22UF 16V 20% X6S  pkg C0805  page 270 : A = SW_P12V_PVCCIN_CPU0_FLT ; B = GND

(kicad_pcb
	(version 20260206)
	(generator "pcbnew")
	(generator_version "10.0")
	(general
		(thickness 1.6)
		(legacy_teardrops no)
	)
	(paper "A4")
	(title_block
		(title "03242023_DA0F0TMBIJ0_F0T_Motherboard_J_brd_V01_OCP.brd")
		(comment 1 "Grand Teton / footprints 5673-5675 of 6105")
	)
	(layers
		(0 "F.Cu" signal "TOP")
		(4 "In1.Cu" signal "GND")
		(6 "In2.Cu" signal "IN1")
		(8 "In3.Cu" signal "GND1")
		(10 "In4.Cu" signal "IN2")
		(12 "In5.Cu" signal "GND2")
		(14 "In6.Cu" signal "IN3")
		(16 "In7.Cu" signal "GND3")
		(18 "In8.Cu" signal "VCC")
		(20 "In9.Cu" signal "VCC1")
		(22 "In10.Cu" signal "GND4")
		(24 "In11.Cu" signal "IN4")
		(26 "In12.Cu" signal "GND5")
		(28 "In13.Cu" signal "IN5")
		(30 "In14.Cu" signal "GND6")
		(32 "In15.Cu" signal "IN6")
		(34 "In16.Cu" signal "GND7")
		(2 "B.Cu" signal "BOTTOM")
		(9 "F.Adhes" user "F.Adhesive")
		(11 "B.Adhes" user "B.Adhesive")
		(13 "F.Paste" user "Package Geometry/Pastemask Top")
		(15 "B.Paste" user "Package Geometry/Pastemask Bottom")
		(5 "F.SilkS" user "Ref Des/Silkscreen Top")
		(7 "B.SilkS" user "Ref Des/Silkscreen Bottom")
		(1 "F.Mask" user "Board Geometry/Soldermask Top")
		(3 "B.Mask" user "Board Geometry/Soldermask Bottom")
		(17 "Dwgs.User" user "User.Drawings")
		(19 "Cmts.User" user "User.Comments")
		(21 "Eco1.User" user "User.Eco1")
		(23 "Eco2.User" user "User.Eco2")
		(25 "Edge.Cuts" user "Board Geometry/Outline")
		(27 "Margin" user)
		(31 "F.CrtYd" user "Package Geometry/Place Bound Top")
		(29 "B.CrtYd" user "Package Geometry/Place Bound Bottom")
		(35 "F.Fab" user "Ref Des/Assembly Top")
		(33 "B.Fab" user "Ref Des/Assembly Bottom")
	)
	(footprint ""
		(layer "B.Cu")
		(at 45.872146 -321.554856 -90)
		(property "Reference" "C61"
			(at 0 0 90)
			(layer "B.SilkS")
			(hide yes)
			(effects
				(font
					(size 1.27 1.27)
				)
				(justify mirror)
			)
		)
		(property "Value" ""
			(at 0 0 90)
			(layer "B.Fab")
			(effects
				(font
					(size 1.27 1.27)
				)
				(justify mirror)
			)
		)
		(duplicate_pad_numbers_are_jumpers no)
		(fp_line
			(start -1.524 0.762)
			(end 1.524 0.762)
			(stroke
				(width 0.1524)
				(type default)
			)
			(layer "B.SilkS")
		)
		(fp_line
			(start 1.524 0.762)
			(end 1.524 -0.762)
			(stroke
				(width 0.1524)
				(type default)
			)
			(layer "B.SilkS")
		)
		(fp_line
			(start -1.524 -0.762)
			(end -1.524 0.762)
			(stroke
				(width 0.1524)
				(type default)
			)
			(layer "B.SilkS")
		)
		(fp_line
			(start 1.524 -0.762)
			(end -1.524 -0.762)
			(stroke
				(width 0.1524)
				(type default)
			)
			(layer "B.SilkS")
		)
		(fp_line
			(start -1.1049 0.724916)
			(end -1.1049 -0.724916)
			(stroke
				(width 0.1)
				(type default)
			)
			(layer "B.Fab")
		)
		(fp_line
			(start 1.1049 0.724916)
			(end -1.1049 0.724916)
			(stroke
				(width 0.1)
				(type default)
			)
			(layer "B.Fab")
		)
		(fp_line
			(start -1.1049 -0.724916)
			(end 1.1049 -0.724916)
			(stroke
				(width 0.1)
				(type default)
			)
			(layer "B.Fab")
		)
		(fp_line
			(start 1.1049 -0.724916)
			(end 1.1049 0.724916)
			(stroke
				(width 0.1)
				(type default)
			)
			(layer "B.Fab")
		)
		(pad "1" smd rect
			(at 0.889 0 270)
			(size 1.016 1.27)
			(layers "B.Cu" "B.Mask" "B.Paste")
			(net "P12V_S3_AUX_CPU1_NVDIMM")
		)
		(pad "2" smd rect
			(at -0.889 0 270)
			(size 1.016 1.27)
			(layers "B.Cu" "B.Mask" "B.Paste")
			(net "GND")
		)
	)
	(footprint ""
		(layer "B.Cu")
		(at 233.5022 -251.879608 -90)
		(property "Reference" "C1884"
			(at 0 0 90)
			(layer "B.SilkS")
			(hide yes)
			(effects
				(font
					(size 1.27 1.27)
				)
				(justify mirror)
			)
		)
		(property "Value" ""
			(at 0 0 90)
			(layer "B.Fab")
			(effects
				(font
					(size 1.27 1.27)
				)
				(justify mirror)
			)
		)
		(duplicate_pad_numbers_are_jumpers no)
		(fp_line
			(start -0.7874 0.4064)
			(end 0.7874 0.4064)
			(stroke
				(width 0.1524)
				(type default)
			)
			(layer "B.SilkS")
		)
		(fp_line
			(start 0.7874 0.4064)
			(end 0.7874 -0.4064)
			(stroke
				(width 0.1524)
				(type default)
			)
			(layer "B.SilkS")
		)
		(fp_line
			(start -0.7874 -0.4064)
			(end -0.7874 0.4064)
			(stroke
				(width 0.1524)
				(type default)
			)
			(layer "B.SilkS")
		)
		(fp_line
			(start 0.7874 -0.4064)
			(end -0.7874 -0.4064)
			(stroke
				(width 0.1524)
				(type default)
			)
			(layer "B.SilkS")
		)
		(fp_line
			(start -0.67945 0.3048)
			(end -0.120396 0.3048)
			(stroke
				(width 0.1)
				(type default)
			)
			(layer "B.Fab")
		)
		(fp_line
			(start -0.120396 0.3048)
			(end -0.120396 0.2794)
			(stroke
				(width 0.1)
				(type default)
			)
			(layer "B.Fab")
		)
		(fp_line
			(start 0.12065 0.3048)
			(end 0.67945 0.3048)
			(stroke
				(width 0.1)
				(type default)
			)
			(layer "B.Fab")
		)
		(fp_line
			(start 0.67945 0.3048)
			(end 0.67945 -0.305054)
			(stroke
				(width 0.1)
				(type default)
			)
			(layer "B.Fab")
		)
		(fp_line
			(start -0.120396 0.2794)
			(end 0.12065 0.2794)
			(stroke
				(width 0.1)
				(type default)
			)
			(layer "B.Fab")
		)
		(fp_line
			(start 0.12065 0.2794)
			(end 0.12065 0.3048)
			(stroke
				(width 0.1)
				(type default)
			)
			(layer "B.Fab")
		)
		(fp_line
			(start -0.12065 -0.2794)
			(end -0.12065 -0.3048)
			(stroke
				(width 0.1)
				(type default)
			)
			(layer "B.Fab")
		)
		(fp_line
			(start 0.12065 -0.2794)
			(end -0.12065 -0.2794)
			(stroke
				(width 0.1)
				(type default)
			)
			(layer "B.Fab")
		)
		(fp_line
			(start -0.67945 -0.3048)
			(end -0.67945 0.3048)
			(stroke
				(width 0.1)
				(type default)
			)
			(layer "B.Fab")
		)
		(fp_line
			(start -0.12065 -0.3048)
			(end -0.67945 -0.3048)
			(stroke
				(width 0.1)
				(type default)
			)
			(layer "B.Fab")
		)
		(fp_line
			(start 0.12065 -0.305054)
			(end 0.12065 -0.2794)
			(stroke
				(width 0.1)
				(type default)
			)
			(layer "B.Fab")
		)
		(fp_line
			(start 0.67945 -0.305054)
			(end 0.12065 -0.305054)
			(stroke
				(width 0.1)
				(type default)
			)
			(layer "B.Fab")
		)
		(pad "1" smd circle
			(at 0.40005 0 90)
			(size 0 0)
			(layers "B.Cu" "B.Mask" "B.Paste")
			(net "VFG_3P3A_CLK_GEN")
		)
		(pad "2" smd circle
			(at -0.40005 0 90)
			(size 0 0)
			(layers "B.Cu" "B.Mask" "B.Paste")
			(net "GND")
		)
	)
	(footprint ""
		(layer "B.Cu")
		(at 329.738228 -342.936576 90)
		(property "Reference" "PC241_P0_7"
			(at 0 0 90)
			(layer "B.SilkS")
			(hide yes)
			(effects
				(font
					(size 1.27 1.27)
				)
				(justify mirror)
			)
		)
		(property "Value" ""
			(at 0 0 90)
			(layer "B.Fab")
			(effects
				(font
					(size 1.27 1.27)
				)
				(justify mirror)
			)
		)
		(duplicate_pad_numbers_are_jumpers no)
		(fp_line
			(start 1.524 -0.762)
			(end -1.524 -0.762)
			(stroke
				(width 0.1524)
				(type default)
			)
			(layer "B.SilkS")
		)
		(fp_line
			(start -1.524 -0.762)
			(end -1.524 0.762)
			(stroke
				(width 0.1524)
				(type default)
			)
			(layer "B.SilkS")
		)
		(fp_line
			(start 1.524 0.762)
			(end 1.524 -0.762)
			(stroke
				(width 0.1524)
				(type default)
			)
			(layer "B.SilkS")
		)
		(fp_line
			(start -1.524 0.762)
			(end 1.524 0.762)
			(stroke
				(width 0.1524)
				(type default)
			)
			(layer "B.SilkS")
		)
		(fp_line
			(start 1.1049 -0.724916)
			(end 1.1049 0.724916)
			(stroke
				(width 0.1)
				(type default)
			)
			(layer "B.Fab")
		)
		(fp_line
			(start -1.1049 -0.724916)
			(end 1.1049 -0.724916)
			(stroke
				(width 0.1)
				(type default)
			)
			(layer "B.Fab")
		)
		(fp_line
			(start 1.1049 0.724916)
			(end -1.1049 0.724916)
			(stroke
				(width 0.1)
				(type default)
			)
			(layer "B.Fab")
		)
		(fp_line
			(start -1.1049 0.724916)
			(end -1.1049 -0.724916)
			(stroke
				(width 0.1)
				(type default)
			)
			(layer "B.Fab")
		)
		(pad "1" smd rect
			(at 0.889 0 90)
			(size 1.016 1.27)
			(layers "B.Cu" "B.Mask" "B.Paste")
			(net "SW_P12V_PVCCIN_CPU0_FLT")
		)
		(pad "2" smd rect
			(at -0.889 0 90)
			(size 1.016 1.27)
			(layers "B.Cu" "B.Mask" "B.Paste")
			(net "GND")
		)
	)
)
